# T6G (Grand Teton) — schematic netlist excerpt (pin names and nets, part order shuffled) for the footprints in the layout excerpt that follows; sources: Cadence DE-HDL packaged netlist, KiCad conversion of 04192023_DAF0TMB3IC0_F0TG_MB_C_brd_V02_OCP.brd

R6278  Q_RES  10K 1% EMPTY  pkg 0402LF  page 179 : A = USB_HUB2_MRP_PRT_CTL4_GANGPWR ; B = GND
R1433  Q_RES  4.7K 5% CHIP  pkg 0201LF  page 353 : A = CLKREQ_RT_CPU1_P3_N ; B = GND
R711  Q_RES  0 5% CHIP  pkg 0201LF  page 321 : A = NCF_A1_CPU1_P0_GND ; B = GND
PL9  Q_INDUCTOR  120NH/69A IND  pkg SMLF  page 203 : \1\ = IND_CPU1_P0_CPL0 ; \2\ = GND

(kicad_pcb
	(version 20260206)
	(generator "pcbnew")
	(generator_version "10.0")
	(general
		(thickness 1.6)
		(legacy_teardrops no)
	)
	(paper "A4")
	(title_block
		(title "04192023_DAF0TMB3IC0_F0TG_MB_C_brd_V02_OCP.brd")
		(comment 1 "Grand Teton / footprints 157-160 of 8354")
	)
	(layers
		(0 "F.Cu" signal "TOP")
		(4 "In1.Cu" signal "GND")
		(6 "In2.Cu" signal "IN1")
		(8 "In3.Cu" signal "GND1")
		(10 "In4.Cu" signal "IN2")
		(12 "In5.Cu" signal "GND2")
		(14 "In6.Cu" signal "IN3")
		(16 "In7.Cu" signal "GND3")
		(18 "In8.Cu" signal "VCC")
		(20 "In9.Cu" signal "VCC1")
		(22 "In10.Cu" signal "GND4")
		(24 "In11.Cu" signal "IN4")
		(26 "In12.Cu" signal "GND5")
		(28 "In13.Cu" signal "IN5")
		(30 "In14.Cu" signal "GND6")
		(32 "In15.Cu" signal "IN6")
		(34 "In16.Cu" signal "GND7")
		(2 "B.Cu" signal "BOTTOM")
		(9 "F.Adhes" user "F.Adhesive")
		(11 "B.Adhes" user "B.Adhesive")
		(13 "F.Paste" user "Package Geometry/Pastemask Top")
		(15 "B.Paste" user "Package Geometry/Pastemask Bottom")
		(5 "F.SilkS" user "Ref Des/Silkscreen Top")
		(7 "B.SilkS" user "Ref Des/Silkscreen Bottom")
		(1 "F.Mask" user "Board Geometry/Soldermask Top")
		(3 "B.Mask" user "Board Geometry/Soldermask Bottom")
		(17 "Dwgs.User" user "User.Drawings")
		(19 "Cmts.User" user "User.Comments")
		(21 "Eco1.User" user "User.Eco1")
		(23 "Eco2.User" user "User.Eco2")
		(25 "Edge.Cuts" user "Board Geometry/Outline")
		(27 "Margin" user)
		(31 "F.CrtYd" user "Package Geometry/Place Bound Top")
		(29 "B.CrtYd" user "Package Geometry/Place Bound Bottom")
		(35 "F.Fab" user "Ref Des/Assembly Top")
		(33 "B.Fab" user "Ref Des/Assembly Bottom")
	)
	(footprint ""
		(layer "F.Cu")
		(at 359.297986 -332.580996 90)
		(property "Reference" "PL9"
			(at -3.302 4.149852 90)
			(unlocked yes)
			(layer "F.SilkS")
			(effects
				(font
					(size 0.7874 0.5842)
					(thickness 0.1524)
				)
				(justify left)
			)
		)
		(property "Value" ""
			(at 0 0 90)
			(layer "F.Fab")
			(effects
				(font
					(size 1.27 1.27)
				)
			)
		)
		(duplicate_pad_numbers_are_jumpers no)
		(fp_line
			(start 3.24993 -3.24993)
			(end 3.24993 -2.2352)
			(stroke
				(width 0.1524)
				(type default)
			)
			(layer "F.SilkS")
		)
		(fp_line
			(start -3.24993 -3.24993)
			(end 3.24993 -3.24993)
			(stroke
				(width 0.1524)
				(type default)
			)
			(layer "F.SilkS")
		)
		(fp_line
			(start -3.24993 -2.2352)
			(end -3.24993 -3.24993)
			(stroke
				(width 0.1524)
				(type default)
			)
			(layer "F.SilkS")
		)
		(fp_line
			(start 3.24993 2.2352)
			(end 3.24993 3.24993)
			(stroke
				(width 0.1524)
				(type default)
			)
			(layer "F.SilkS")
		)
		(fp_line
			(start 3.24993 3.24993)
			(end -3.24993 3.24993)
			(stroke
				(width 0.1524)
				(type default)
			)
			(layer "F.SilkS")
		)
		(fp_line
			(start -3.24993 3.24993)
			(end -3.24993 2.2352)
			(stroke
				(width 0.1524)
				(type default)
			)
			(layer "F.SilkS")
		)
		(fp_line
			(start 3.24993 -3.24993)
			(end 3.24993 3.24993)
			(stroke
				(width 0.1)
				(type default)
			)
			(layer "F.Fab")
		)
		(fp_line
			(start -3.24993 -3.24993)
			(end 3.24993 -3.24993)
			(stroke
				(width 0.1)
				(type default)
			)
			(layer "F.Fab")
		)
		(fp_line
			(start 3.24993 3.24993)
			(end -3.24993 3.24993)
			(stroke
				(width 0.1)
				(type default)
			)
			(layer "F.Fab")
		)
		(fp_line
			(start -3.24993 3.24993)
			(end -3.24993 -3.24993)
			(stroke
				(width 0.1)
				(type default)
			)
			(layer "F.Fab")
		)
		(pad "1" smd rect
			(at -2.29997 0 90)
			(size 2.0066 4.2164)
			(layers "F.Cu" "F.Mask" "F.Paste")
			(net "IND_CPU1_P0_CPL0")
		)
		(pad "2" smd rect
			(at 2.29997 0 90)
			(size 2.0066 4.2164)
			(layers "F.Cu" "F.Mask" "F.Paste")
			(net "GND")
		)
	)
	(footprint ""
		(layer "F.Cu")
		(at 68.98132 -394.5382 -90)
		(property "Reference" "R711"
			(at 0 0 270)
			(layer "F.SilkS")
			(hide yes)
			(effects
				(font
					(size 1.27 1.27)
				)
			)
		)
		(property "Value" ""
			(at 0 0 270)
			(layer "F.Fab")
			(effects
				(font
					(size 1.27 1.27)
				)
			)
		)
		(duplicate_pad_numbers_are_jumpers no)
		(fp_line
			(start -0.32512 0.175006)
			(end -0.32512 -0.175006)
			(stroke
				(width 0.1)
				(type default)
			)
			(layer "F.Fab")
		)
		(fp_line
			(start 0.32512 0.175006)
			(end -0.32512 0.175006)
			(stroke
				(width 0.1)
				(type default)
			)
			(layer "F.Fab")
		)
		(fp_line
			(start -0.32512 -0.175006)
			(end 0.32512 -0.175006)
			(stroke
				(width 0.1)
				(type default)
			)
			(layer "F.Fab")
		)
		(fp_line
			(start 0.32512 -0.175006)
			(end 0.32512 0.175006)
			(stroke
				(width 0.1)
				(type default)
			)
			(layer "F.Fab")
		)
		(pad "1" smd rect
			(at -0.2667 0 270)
			(size 0.3048 0.381)
			(layers "F.Cu" "F.Mask" "F.Paste")
			(net "NCF_A1_CPU1_P0_GND")
		)
		(pad "2" smd rect
			(at 0.2667 0 90)
			(size 0.3048 0.381)
			(layers "F.Cu" "F.Mask" "F.Paste")
			(net "GND")
		)
	)
	(footprint ""
		(layer "F.Cu")
		(at 138.067542 -381.7874)
		(property "Reference" "R1433"
			(at 0 0 0)
			(layer "F.SilkS")
			(hide yes)
			(effects
				(font
					(size 1.27 1.27)
				)
			)
		)
		(property "Value" ""
			(at 0 0 0)
			(layer "F.Fab")
			(effects
				(font
					(size 1.27 1.27)
				)
			)
		)
		(duplicate_pad_numbers_are_jumpers no)
		(fp_line
			(start -0.32512 -0.175006)
			(end 0.32512 -0.175006)
			(stroke
				(width 0.1)
				(type default)
			)
			(layer "F.Fab")
		)
		(fp_line
			(start -0.32512 0.175006)
			(end -0.32512 -0.175006)
			(stroke
				(width 0.1)
				(type default)
			)
			(layer "F.Fab")
		)
		(fp_line
			(start 0.32512 -0.175006)
			(end 0.32512 0.175006)
			(stroke
				(width 0.1)
				(type default)
			)
			(layer "F.Fab")
		)
		(fp_line
			(start 0.32512 0.175006)
			(end -0.32512 0.175006)
			(stroke
				(width 0.1)
				(type default)
			)
			(layer "F.Fab")
		)
		(pad "1" smd rect
			(at -0.2667 0)
			(size 0.3048 0.381)
			(layers "F.Cu" "F.Mask" "F.Paste")
			(net "CLKREQ_RT_CPU1_P3_N")
		)
		(pad "2" smd rect
			(at 0.2667 0 180)
			(size 0.3048 0.381)
			(layers "F.Cu" "F.Mask" "F.Paste")
			(net "GND")
		)
	)
	(footprint ""
		(layer "F.Cu")
		(at 124.840238 -43.59275)
		(property "Reference" "R6278"
			(at 0 0 0)
			(layer "F.SilkS")
			(hide yes)
			(effects
				(font
					(size 1.27 1.27)
				)
			)
		)
		(property "Value" ""
			(at 0 0 0)
			(layer "F.Fab")
			(effects
				(font
					(size 1.27 1.27)
				)
			)
		)
		(duplicate_pad_numbers_are_jumpers no)
		(fp_line
			(start -0.7874 -0.4064)
			(end 0.7874 -0.4064)
			(stroke
				(width 0.1524)
				(type default)
			)
			(layer "F.SilkS")
		)
		(fp_line
			(start -0.7874 0.4064)
			(end -0.7874 -0.4064)
			(stroke
				(width 0.1524)
				(type default)
			)
			(layer "F.SilkS")
		)
		(fp_line
			(start 0.7874 -0.4064)
			(end 0.7874 0.4064)
			(stroke
				(width 0.1524)
				(type default)
			)
			(layer "F.SilkS")
		)
		(fp_line
			(start 0.7874 0.4064)
			(end -0.7874 0.4064)
			(stroke
				(width 0.1524)
				(type default)
			)
			(layer "F.SilkS")
		)
		(fp_line
			(start -0.67945 -0.305054)
			(end -0.12065 -0.305054)
			(stroke
				(width 0.1)
				(type default)
			)
			(layer "F.Fab")
		)
		(fp_line
			(start -0.67945 0.3048)
			(end -0.67945 -0.305054)
			(stroke
				(width 0.1)
				(type default)
			)
			(layer "F.Fab")
		)
		(fp_line
			(start -0.12065 -0.305054)
			(end -0.12065 -0.2794)
			(stroke
				(width 0.1)
				(type default)
			)
			(layer "F.Fab")
		)
		(fp_line
			(start -0.12065 -0.2794)
			(end 0.12065 -0.2794)
			(stroke
				(width 0.1)
				(type default)
			)
			(layer "F.Fab")
		)
		(fp_line
			(start -0.12065 0.2794)
			(end -0.12065 0.3048)
			(stroke
				(width 0.1)
				(type default)
			)
			(layer "F.Fab")
		)
		(fp_line
			(start -0.12065 0.3048)
			(end -0.67945 0.3048)
			(stroke
				(width 0.1)
				(type default)
			)
			(layer "F.Fab")
		)
		(fp_line
			(start 0.120396 0.2794)
			(end -0.12065 0.2794)
			(stroke
				(width 0.1)
				(type default)
			)
			(layer "F.Fab")
		)
		(fp_line
			(start 0.120396 0.3048)
			(end 0.120396 0.2794)
			(stroke
				(width 0.1)
				(type default)
			)
			(layer "F.Fab")
		)
		(fp_line
			(start 0.12065 -0.3048)
			(end 0.67945 -0.3048)
			(stroke
				(width 0.1)
				(type default)
			)
			(layer "F.Fab")
		)
		(fp_line
			(start 0.12065 -0.2794)
			(end 0.12065 -0.3048)
			(stroke
				(width 0.1)
				(type default)
			)
			(layer "F.Fab")
		)
		(fp_line
			(start 0.67945 -0.3048)
			(end 0.67945 0.3048)
			(stroke
				(width 0.1)
				(type default)
			)
			(layer "F.Fab")
		)
		(fp_line
			(start 0.67945 0.3048)
			(end 0.120396 0.3048)
			(stroke
				(width 0.1)
				(type default)
			)
			(layer "F.Fab")
		)
		(pad "1" smd circle
			(at -0.40005 0)
			(size 0 0)
			(layers "F.Cu" "F.Mask" "F.Paste")
			(net "USB_HUB2_MRP_PRT_CTL4_GANGPWR")
		)
		(pad "2" smd circle
			(at 0.40005 0)
			(size 0 0)
			(layers "F.Cu" "F.Mask" "F.Paste")
			(net "GND")
		)
	)
)
